(kicad_pcb
	(version 20260206)
	(generator "pcbnew")
	(generator_version "10.0")
	(general
		(thickness 1.6)
		(legacy_teardrops no)
	)
	(paper "A4")
	(title_block
		(title "03242023_DA0F0TMBIJ0_F0T_Motherboard_J_brd_V01_OCP.brd")
		(comment 1 "Grand Teton / footprints 5577-5583 of 6105")
	)
	(layers
		(0 "F.Cu" signal "TOP")
		(4 "In1.Cu" signal "GND")
		(6 "In2.Cu" signal "IN1")
		(8 "In3.Cu" signal "GND1")
		(10 "In4.Cu" signal "IN2")
		(12 "In5.Cu" signal "GND2")
		(14 "In6.Cu" signal "IN3")
		(16 "In7.Cu" signal "GND3")
		(18 "In8.Cu" signal "VCC")
		(20 "In9.Cu" signal "VCC1")
		(22 "In10.Cu" signal "GND4")
		(24 "In11.Cu" signal "IN4")
		(26 "In12.Cu" signal "GND5")
		(28 "In13.Cu" signal "IN5")
		(30 "In14.Cu" signal "GND6")
		(32 "In15.Cu" signal "IN6")
		(34 "In16.Cu" signal "GND7")
		(2 "B.Cu" signal "BOTTOM")
		(9 "F.Adhes" user "F.Adhesive")
		(11 "B.Adhes" user "B.Adhesive")
		(13 "F.Paste" user "Package Geometry/Pastemask Top")
		(15 "B.Paste" user "Package Geometry/Pastemask Bottom")
		(5 "F.SilkS" user "Ref Des/Silkscreen Top")
		(7 "B.SilkS" user "Ref Des/Silkscreen Bottom")
		(1 "F.Mask" user "Board Geometry/Soldermask Top")
		(3 "B.Mask" user "Board Geometry/Soldermask Bottom")
		(17 "Dwgs.User" user "User.Drawings")
		(19 "Cmts.User" user "User.Comments")
		(21 "Eco1.User" user "User.Eco1")
		(23 "Eco2.User" user "User.Eco2")
		(25 "Edge.Cuts" user "Board Geometry/Outline")
		(27 "Margin" user)
		(31 "F.CrtYd" user "Package Geometry/Place Bound Top")
		(29 "B.CrtYd" user "Package Geometry/Place Bound Bottom")
		(35 "F.Fab" user "Ref Des/Assembly Top")
		(33 "B.Fab" user "Ref Des/Assembly Bottom")
	)
	(footprint ""
		(layer "B.Cu")
		(at 60.978288 -250.767596 90)
		(property "Reference" "C462"
			(at 0 0 90)
			(layer "B.SilkS")
			(hide yes)
			(effects
				(font
					(size 1.27 1.27)
				)
				(justify mirror)
			)
		)
		(property "Value" ""
			(at 0 0 90)
			(layer "B.Fab")
			(effects
				(font
					(size 1.27 1.27)
				)
				(justify mirror)
			)
		)
		(duplicate_pad_numbers_are_jumpers no)
		(fp_line
			(start 1.524 -0.762)
			(end -1.524 -0.762)
			(stroke
				(width 0.1524)
				(type default)
			)
			(layer "B.SilkS")
		)
		(fp_line
			(start -1.524 -0.762)
			(end -1.524 0.762)
			(stroke
				(width 0.1524)
				(type default)
			)
			(layer "B.SilkS")
		)
		(fp_line
			(start 1.524 0.762)
			(end 1.524 -0.762)
			(stroke
				(width 0.1524)
				(type default)
			)
			(layer "B.SilkS")
		)
		(fp_line
			(start -1.524 0.762)
			(end 1.524 0.762)
			(stroke
				(width 0.1524)
				(type default)
			)
			(layer "B.SilkS")
		)
		(fp_line
			(start 1.1049 -0.724916)
			(end 1.1049 0.724916)
			(stroke
				(width 0.1)
				(type default)
			)
			(layer "B.Fab")
		)
		(fp_line
			(start -1.1049 -0.724916)
			(end 1.1049 -0.724916)
			(stroke
				(width 0.1)
				(type default)
			)
			(layer "B.Fab")
		)
		(fp_line
			(start 1.1049 0.724916)
			(end -1.1049 0.724916)
			(stroke
				(width 0.1)
				(type default)
			)
			(layer "B.Fab")
		)
		(fp_line
			(start -1.1049 0.724916)
			(end -1.1049 -0.724916)
			(stroke
				(width 0.1)
				(type default)
			)
			(layer "B.Fab")
		)
		(pad "1" smd rect
			(at 0.889 0 90)
			(size 1.016 1.27)
			(layers "B.Cu" "B.Mask" "B.Paste")
			(net "PVCCFA_EHV_FIVRA_CPU1")
		)
		(pad "2" smd rect
			(at -0.889 0 90)
			(size 1.016 1.27)
			(layers "B.Cu" "B.Mask" "B.Paste")
			(net "GND")
		)
	)
	(footprint ""
		(layer "B.Cu")
		(at 193.065146 -321.554856 -90)
		(property "Reference" "C79"
			(at 0 0 90)
			(layer "B.SilkS")
			(hide yes)
			(effects
				(font
					(size 1.27 1.27)
				)
				(justify mirror)
			)
		)
		(property "Value" ""
			(at 0 0 90)
			(layer "B.Fab")
			(effects
				(font
					(size 1.27 1.27)
				)
				(justify mirror)
			)
		)
		(duplicate_pad_numbers_are_jumpers no)
		(fp_line
			(start -1.524 0.762)
			(end 1.524 0.762)
			(stroke
				(width 0.1524)
				(type default)
			)
			(layer "B.SilkS")
		)
		(fp_line
			(start 1.524 0.762)
			(end 1.524 -0.762)
			(stroke
				(width 0.1524)
				(type default)
			)
			(layer "B.SilkS")
		)
		(fp_line
			(start -1.524 -0.762)
			(end -1.524 0.762)
			(stroke
				(width 0.1524)
				(type default)
			)
			(layer "B.SilkS")
		)
		(fp_line
			(start 1.524 -0.762)
			(end -1.524 -0.762)
			(stroke
				(width 0.1524)
				(type default)
			)
			(layer "B.SilkS")
		)
		(fp_line
			(start -1.1049 0.724916)
			(end -1.1049 -0.724916)
			(stroke
				(width 0.1)
				(type default)
			)
			(layer "B.Fab")
		)
		(fp_line
			(start 1.1049 0.724916)
			(end -1.1049 0.724916)
			(stroke
				(width 0.1)
				(type default)
			)
			(layer "B.Fab")
		)
		(fp_line
			(start -1.1049 -0.724916)
			(end 1.1049 -0.724916)
			(stroke
				(width 0.1)
				(type default)
			)
			(layer "B.Fab")
		)
		(fp_line
			(start 1.1049 -0.724916)
			(end 1.1049 0.724916)
			(stroke
				(width 0.1)
				(type default)
			)
			(layer "B.Fab")
		)
		(pad "1" smd rect
			(at 0.889 0 270)
			(size 1.016 1.27)
			(layers "B.Cu" "B.Mask" "B.Paste")
			(net "P12V_S3_AUX_CPU1_NVDIMM")
		)
		(pad "2" smd rect
			(at -0.889 0 270)
			(size 1.016 1.27)
			(layers "B.Cu" "B.Mask" "B.Paste")
			(net "GND")
		)
	)
	(footprint ""
		(layer "B.Cu")
		(at 100.306886 -356.63759)
		(property "Reference" "R2553"
			(at 0 0 0)
			(layer "B.SilkS")
			(hide yes)
			(effects
				(font
					(size 1.27 1.27)
				)
				(justify mirror)
			)
		)
		(property "Value" ""
			(at 0 0 0)
			(layer "B.Fab")
			(effects
				(font
					(size 1.27 1.27)
				)
				(justify mirror)
			)
		)
		(duplicate_pad_numbers_are_jumpers no)
		(fp_line
			(start -0.7874 -0.4064)
			(end -0.7874 0.4064)
			(stroke
				(width 0.1524)
				(type default)
			)
			(layer "B.SilkS")
		)
		(fp_line
			(start -0.7874 0.4064)
			(end 0.7874 0.4064)
			(stroke
				(width 0.1524)
				(type default)
			)
			(layer "B.SilkS")
		)
		(fp_line
			(start 0.7874 -0.4064)
			(end -0.7874 -0.4064)
			(stroke
				(width 0.1524)
				(type default)
			)
			(layer "B.SilkS")
		)
		(fp_line
			(start 0.7874 0.4064)
			(end 0.7874 -0.4064)
			(stroke
				(width 0.1524)
				(type default)
			)
			(layer "B.SilkS")
		)
		(fp_line
			(start -0.67945 -0.3048)
			(end -0.67945 0.3048)
			(stroke
				(width 0.1)
				(type default)
			)
			(layer "B.Fab")
		)
		(fp_line
			(start -0.67945 0.3048)
			(end -0.120396 0.3048)
			(stroke
				(width 0.1)
				(type default)
			)
			(layer "B.Fab")
		)
		(fp_line
			(start -0.12065 -0.3048)
			(end -0.67945 -0.3048)
			(stroke
				(width 0.1)
				(type default)
			)
			(layer "B.Fab")
		)
		(fp_line
			(start -0.12065 -0.2794)
			(end -0.12065 -0.3048)
			(stroke
				(width 0.1)
				(type default)
			)
			(layer "B.Fab")
		)
		(fp_line
			(start -0.120396 0.2794)
			(end 0.12065 0.2794)
			(stroke
				(width 0.1)
				(type default)
			)
			(layer "B.Fab")
		)
		(fp_line
			(start -0.120396 0.3048)
			(end -0.120396 0.2794)
			(stroke
				(width 0.1)
				(type default)
			)
			(layer "B.Fab")
		)
		(fp_line
			(start 0.12065 -0.305054)
			(end 0.12065 -0.2794)
			(stroke
				(width 0.1)
				(type default)
			)
			(layer "B.Fab")
		)
		(fp_line
			(start 0.12065 -0.2794)
			(end -0.12065 -0.2794)
			(stroke
				(width 0.1)
				(type default)
			)
			(layer "B.Fab")
		)
		(fp_line
			(start 0.12065 0.2794)
			(end 0.12065 0.3048)
			(stroke
				(width 0.1)
				(type default)
			)
			(layer "B.Fab")
		)
		(fp_line
			(start 0.12065 0.3048)
			(end 0.67945 0.3048)
			(stroke
				(width 0.1)
				(type default)
			)
			(layer "B.Fab")
		)
		(fp_line
			(start 0.67945 -0.305054)
			(end 0.12065 -0.305054)
			(stroke
				(width 0.1)
				(type default)
			)
			(layer "B.Fab")
		)
		(fp_line
			(start 0.67945 0.3048)
			(end 0.67945 -0.305054)
			(stroke
				(width 0.1)
				(type default)
			)
			(layer "B.Fab")
		)
		(pad "1" smd circle
			(at 0.40005 0 180)
			(size 0 0)
			(layers "B.Cu" "B.Mask" "B.Paste")
			(net "SVID_DIO0_CPU1_R")
		)
		(pad "2" smd circle
			(at -0.40005 0 180)
			(size 0 0)
			(layers "B.Cu" "B.Mask" "B.Paste")
			(net "PVNN_TERM_CPU1")
		)
	)
	(footprint ""
		(layer "B.Cu")
		(at 118.18112 -248.49836 -90)
		(property "Reference" "C323"
			(at 0 0 90)
			(layer "B.SilkS")
			(hide yes)
			(effects
				(font
					(size 1.27 1.27)
				)
				(justify mirror)
			)
		)
		(property "Value" ""
			(at 0 0 90)
			(layer "B.Fab")
			(effects
				(font
					(size 1.27 1.27)
				)
				(justify mirror)
			)
		)
		(duplicate_pad_numbers_are_jumpers no)
		(fp_line
			(start -1.524 0.762)
			(end 1.524 0.762)
			(stroke
				(width 0.1524)
				(type default)
			)
			(layer "B.SilkS")
		)
		(fp_line
			(start 1.524 0.762)
			(end 1.524 -0.762)
			(stroke
				(width 0.1524)
				(type default)
			)
			(layer "B.SilkS")
		)
		(fp_line
			(start -1.524 -0.762)
			(end -1.524 0.762)
			(stroke
				(width 0.1524)
				(type default)
			)
			(layer "B.SilkS")
		)
		(fp_line
			(start 1.524 -0.762)
			(end -1.524 -0.762)
			(stroke
				(width 0.1524)
				(type default)
			)
			(layer "B.SilkS")
		)
		(fp_line
			(start -1.1049 0.724916)
			(end -1.1049 -0.724916)
			(stroke
				(width 0.1)
				(type default)
			)
			(layer "B.Fab")
		)
		(fp_line
			(start 1.1049 0.724916)
			(end -1.1049 0.724916)
			(stroke
				(width 0.1)
				(type default)
			)
			(layer "B.Fab")
		)
		(fp_line
			(start -1.1049 -0.724916)
			(end 1.1049 -0.724916)
			(stroke
				(width 0.1)
				(type default)
			)
			(layer "B.Fab")
		)
		(fp_line
			(start 1.1049 -0.724916)
			(end 1.1049 0.724916)
			(stroke
				(width 0.1)
				(type default)
			)
			(layer "B.Fab")
		)
		(pad "1" smd rect
			(at 0.889 0 270)
			(size 1.016 1.27)
			(layers "B.Cu" "B.Mask" "B.Paste")
			(net "PVCCIN_CPU1")
		)
		(pad "2" smd rect
			(at -0.889 0 270)
			(size 1.016 1.27)
			(layers "B.Cu" "B.Mask" "B.Paste")
			(net "GND")
		)
	)
	(footprint ""
		(layer "B.Cu")
		(at 341.272114 -30.636972 180)
		(property "Reference" "R1306"
			(at 0 0 0)
			(layer "B.SilkS")
			(hide yes)
			(effects
				(font
					(size 1.27 1.27)
				)
				(justify mirror)
			)
		)
		(property "Value" ""
			(at 0 0 0)
			(layer "B.Fab")
			(effects
				(font
					(size 1.27 1.27)
				)
				(justify mirror)
			)
		)
		(duplicate_pad_numbers_are_jumpers no)
		(fp_line
			(start 0.7874 0.4064)
			(end 0.7874 -0.4064)
			(stroke
				(width 0.1524)
				(type default)
			)
			(layer "B.SilkS")
		)
		(fp_line
			(start 0.7874 -0.4064)
			(end -0.7874 -0.4064)
			(stroke
				(width 0.1524)
				(type default)
			)
			(layer "B.SilkS")
		)
		(fp_line
			(start -0.7874 0.4064)
			(end 0.7874 0.4064)
			(stroke
				(width 0.1524)
				(type default)
			)
			(layer "B.SilkS")
		)
		(fp_line
			(start -0.7874 -0.4064)
			(end -0.7874 0.4064)
			(stroke
				(width 0.1524)
				(type default)
			)
			(layer "B.SilkS")
		)
		(fp_line
			(start 0.67945 0.3048)
			(end 0.67945 -0.305054)
			(stroke
				(width 0.1)
				(type default)
			)
			(layer "B.Fab")
		)
		(fp_line
			(start 0.67945 -0.305054)
			(end 0.12065 -0.305054)
			(stroke
				(width 0.1)
				(type default)
			)
			(layer "B.Fab")
		)
		(fp_line
			(start 0.12065 0.3048)
			(end 0.67945 0.3048)
			(stroke
				(width 0.1)
				(type default)
			)
			(layer "B.Fab")
		)
		(fp_line
			(start 0.12065 0.2794)
			(end 0.12065 0.3048)
			(stroke
				(width 0.1)
				(type default)
			)
			(layer "B.Fab")
		)
		(fp_line
			(start 0.12065 -0.2794)
			(end -0.12065 -0.2794)
			(stroke
				(width 0.1)
				(type default)
			)
			(layer "B.Fab")
		)
		(fp_line
			(start 0.12065 -0.305054)
			(end 0.12065 -0.2794)
			(stroke
				(width 0.1)
				(type default)
			)
			(layer "B.Fab")
		)
		(fp_line
			(start -0.120396 0.3048)
			(end -0.120396 0.2794)
			(stroke
				(width 0.1)
				(type default)
			)
			(layer "B.Fab")
		)
		(fp_line
			(start -0.120396 0.2794)
			(end 0.12065 0.2794)
			(stroke
				(width 0.1)
				(type default)
			)
			(layer "B.Fab")
		)
		(fp_line
			(start -0.12065 -0.2794)
			(end -0.12065 -0.3048)
			(stroke
				(width 0.1)
				(type default)
			)
			(layer "B.Fab")
		)
		(fp_line
			(start -0.12065 -0.3048)
			(end -0.67945 -0.3048)
			(stroke
				(width 0.1)
				(type default)
			)
			(layer "B.Fab")
		)
		(fp_line
			(start -0.67945 0.3048)
			(end -0.120396 0.3048)
			(stroke
				(width 0.1)
				(type default)
			)
			(layer "B.Fab")
		)
		(fp_line
			(start -0.67945 -0.3048)
			(end -0.67945 0.3048)
			(stroke
				(width 0.1)
				(type default)
			)
			(layer "B.Fab")
		)
		(pad "1" smd circle
			(at 0.40005 0)
			(size 0 0)
			(layers "B.Cu" "B.Mask" "B.Paste")
			(net "FM_PS_PWROK_DLY_R_SEL")
		)
		(pad "2" smd circle
			(at -0.40005 0)
			(size 0 0)
			(layers "B.Cu" "B.Mask" "B.Paste")
			(net "FM_PS_PWROK_DLY_SEL")
		)
	)
	(footprint ""
		(layer "B.Cu")
		(at 396.97406 -61.448188 90)
		(property "Reference" "C550"
			(at 0 0 90)
			(layer "B.SilkS")
			(hide yes)
			(effects
				(font
					(size 1.27 1.27)
				)
				(justify mirror)
			)
		)
		(property "Value" ""
			(at 0 0 90)
			(layer "B.Fab")
			(effects
				(font
					(size 1.27 1.27)
				)
				(justify mirror)
			)
		)
		(duplicate_pad_numbers_are_jumpers no)
		(fp_line
			(start 0.7874 -0.4064)
			(end -0.7874 -0.4064)
			(stroke
				(width 0.1524)
				(type default)
			)
			(layer "B.SilkS")
		)
		(fp_line
			(start -0.7874 -0.4064)
			(end -0.7874 0.4064)
			(stroke
				(width 0.1524)
				(type default)
			)
			(layer "B.SilkS")
		)
		(fp_line
			(start 0.7874 0.4064)
			(end 0.7874 -0.4064)
			(stroke
				(width 0.1524)
				(type default)
			)
			(layer "B.SilkS")
		)
		(fp_line
			(start -0.7874 0.4064)
			(end 0.7874 0.4064)
			(stroke
				(width 0.1524)
				(type default)
			)
			(layer "B.SilkS")
		)
		(fp_line
			(start 0.67945 -0.305054)
			(end 0.12065 -0.305054)
			(stroke
				(width 0.1)
				(type default)
			)
			(layer "B.Fab")
		)
		(fp_line
			(start 0.12065 -0.305054)
			(end 0.12065 -0.2794)
			(stroke
				(width 0.1)
				(type default)
			)
			(layer "B.Fab")
		)
		(fp_line
			(start -0.12065 -0.3048)
			(end -0.67945 -0.3048)
			(stroke
				(width 0.1)
				(type default)
			)
			(layer "B.Fab")
		)
		(fp_line
			(start -0.67945 -0.3048)
			(end -0.67945 0.3048)
			(stroke
				(width 0.1)
				(type default)
			)
			(layer "B.Fab")
		)
		(fp_line
			(start 0.12065 -0.2794)
			(end -0.12065 -0.2794)
			(stroke
				(width 0.1)
				(type default)
			)
			(layer "B.Fab")
		)
		(fp_line
			(start -0.12065 -0.2794)
			(end -0.12065 -0.3048)
			(stroke
				(width 0.1)
				(type default)
			)
			(layer "B.Fab")
		)
		(fp_line
			(start 0.12065 0.2794)
			(end 0.12065 0.3048)
			(stroke
				(width 0.1)
				(type default)
			)
			(layer "B.Fab")
		)
		(fp_line
			(start -0.120396 0.2794)
			(end 0.12065 0.2794)
			(stroke
				(width 0.1)
				(type default)
			)
			(layer "B.Fab")
		)
		(fp_line
			(start 0.67945 0.3048)
			(end 0.67945 -0.305054)
			(stroke
				(width 0.1)
				(type default)
			)
			(layer "B.Fab")
		)
		(fp_line
			(start 0.12065 0.3048)
			(end 0.67945 0.3048)
			(stroke
				(width 0.1)
				(type default)
			)
			(layer "B.Fab")
		)
		(fp_line
			(start -0.120396 0.3048)
			(end -0.120396 0.2794)
			(stroke
				(width 0.1)
				(type default)
			)
			(layer "B.Fab")
		)
		(fp_line
			(start -0.67945 0.3048)
			(end -0.120396 0.3048)
			(stroke
				(width 0.1)
				(type default)
			)
			(layer "B.Fab")
		)
		(pad "1" smd circle
			(at 0.40005 0 270)
			(size 0 0)
			(layers "B.Cu" "B.Mask" "B.Paste")
			(net "P1V8_PCH_AUX")
		)
		(pad "2" smd circle
			(at -0.40005 0 270)
			(size 0 0)
			(layers "B.Cu" "B.Mask" "B.Paste")
			(net "GND")
		)
	)
	(footprint ""
		(layer "B.Cu")
		(at 166.165784 -316.592458 90)
		(property "Reference" "R3899"
			(at 0 0 90)
			(layer "B.SilkS")
			(hide yes)
			(effects
				(font
					(size 1.27 1.27)
				)
				(justify mirror)
			)
		)
		(property "Value" ""
			(at 0 0 90)
			(layer "B.Fab")
			(effects
				(font
					(size 1.27 1.27)
				)
				(justify mirror)
			)
		)
		(duplicate_pad_numbers_are_jumpers no)
		(fp_line
			(start 0.7874 -0.4064)
			(end -0.7874 -0.4064)
			(stroke
				(width 0.1524)
				(type default)
			)
			(layer "B.SilkS")
		)
		(fp_line
			(start -0.7874 -0.4064)
			(end -0.7874 0.4064)
			(stroke
				(width 0.1524)
				(type default)
			)
			(layer "B.SilkS")
		)
		(fp_line
			(start 0.7874 0.4064)
			(end 0.7874 -0.4064)
			(stroke
				(width 0.1524)
				(type default)
			)
			(layer "B.SilkS")
		)
		(fp_line
			(start -0.7874 0.4064)
			(end 0.7874 0.4064)
			(stroke
				(width 0.1524)
				(type default)
			)
			(layer "B.SilkS")
		)
		(fp_line
			(start 0.67945 -0.305054)
			(end 0.12065 -0.305054)
			(stroke
				(width 0.1)
				(type default)
			)
			(layer "B.Fab")
		)
		(fp_line
			(start 0.12065 -0.305054)
			(end 0.12065 -0.2794)
			(stroke
				(width 0.1)
				(type default)
			)
			(layer "B.Fab")
		)
		(fp_line
			(start -0.12065 -0.3048)
			(end -0.67945 -0.3048)
			(stroke
				(width 0.1)
				(type default)
			)
			(layer "B.Fab")
		)
		(fp_line
			(start -0.67945 -0.3048)
			(end -0.67945 0.3048)
			(stroke
				(width 0.1)
				(type default)
			)
			(layer "B.Fab")
		)
		(fp_line
			(start 0.12065 -0.2794)
			(end -0.12065 -0.2794)
			(stroke
				(width 0.1)
				(type default)
			)
			(layer "B.Fab")
		)
		(fp_line
			(start -0.12065 -0.2794)
			(end -0.12065 -0.3048)
			(stroke
				(width 0.1)
				(type default)
			)
			(layer "B.Fab")
		)
		(fp_line
			(start 0.12065 0.2794)
			(end 0.12065 0.3048)
			(stroke
				(width 0.1)
				(type default)
			)
			(layer "B.Fab")
		)
		(fp_line
			(start -0.120396 0.2794)
			(end 0.12065 0.2794)
			(stroke
				(width 0.1)
				(type default)
			)
			(layer "B.Fab")
		)
		(fp_line
			(start 0.67945 0.3048)
			(end 0.67945 -0.305054)
			(stroke
				(width 0.1)
				(type default)
			)
			(layer "B.Fab")
		)
		(fp_line
			(start 0.12065 0.3048)
			(end 0.67945 0.3048)
			(stroke
				(width 0.1)
				(type default)
			)
			(layer "B.Fab")
		)
		(fp_line
			(start -0.120396 0.3048)
			(end -0.120396 0.2794)
			(stroke
				(width 0.1)
				(type default)
			)
			(layer "B.Fab")
		)
		(fp_line
			(start -0.67945 0.3048)
			(end -0.120396 0.3048)
			(stroke
				(width 0.1)
				(type default)
			)
			(layer "B.Fab")
		)
		(pad "1" smd circle
			(at 0.40005 0 270)
			(size 0 0)
			(layers "B.Cu" "B.Mask" "B.Paste")
			(net "I3C_SPD_DDREFGH_CPU1_LVC1_SCL_R")
		)
		(pad "2" smd circle
			(at -0.40005 0 270)
			(size 0 0)
			(layers "B.Cu" "B.Mask" "B.Paste")
			(net "I3C_SPD_DDREFGH_CPU1_LVC1_SCL")
		)
	)
)
